(kicad_pcb
	(version 20260206)
	(generator "pcbnew")
	(generator_version "10.0")
	(general
		(thickness 1.6)
		(legacy_teardrops no)
	)
	(paper "A4")
	(title_block
		(title "Wiwynn_Tioga_Pass_MB.brd")
		(comment 1 "Tioga Pass / footprints 500-506 of 4770")
	)
	(layers
		(0 "F.Cu" signal "TOP")
		(4 "In1.Cu" signal "L2GND")
		(6 "In2.Cu" signal "L3")
		(8 "In3.Cu" signal "L4GND")
		(10 "In4.Cu" signal "L5")
		(12 "In5.Cu" signal "L6GND")
		(14 "In6.Cu" signal "L7VCC")
		(16 "In7.Cu" signal "L8VCC")
		(18 "In8.Cu" signal "L9GND")
		(20 "In9.Cu" signal "L10")
		(22 "In10.Cu" signal "L11GND")
		(24 "In11.Cu" signal "L12")
		(26 "In12.Cu" signal "L13GND")
		(2 "B.Cu" signal "BOTTOM")
		(9 "F.Adhes" user "F.Adhesive")
		(11 "B.Adhes" user "B.Adhesive")
		(13 "F.Paste" user "Package Geometry/Pastemask Top")
		(15 "B.Paste" user "Package Geometry/Pastemask Bottom")
		(5 "F.SilkS" user "Ref Des/Silkscreen Top")
		(7 "B.SilkS" user "Ref Des/Silkscreen Bottom")
		(1 "F.Mask" user "Board Geometry/Soldermask Top")
		(3 "B.Mask" user "Board Geometry/Soldermask Bottom")
		(17 "Dwgs.User" user "User.Drawings")
		(19 "Cmts.User" user "User.Comments")
		(21 "Eco1.User" user "User.Eco1")
		(23 "Eco2.User" user "User.Eco2")
		(25 "Edge.Cuts" user "Board Geometry/Outline")
		(27 "Margin" user)
		(31 "F.CrtYd" user "Package Geometry/Place Bound Top")
		(29 "B.CrtYd" user "Package Geometry/Place Bound Bottom")
		(35 "F.Fab" user "Ref Des/Assembly Top")
		(33 "B.Fab" user "Ref Des/Assembly Bottom")
	)
	(footprint ""
		(layer "F.Cu")
		(at 175.387 -85.217 90)
		(property "Reference" "R4D10"
			(at 0 0 90)
			(layer "F.SilkS")
			(hide yes)
			(effects
				(font
					(size 1.27 1.27)
				)
			)
		)
		(property "Value" ""
			(at 0 0 90)
			(layer "F.Fab")
			(effects
				(font
					(size 1.27 1.27)
				)
			)
		)
		(duplicate_pad_numbers_are_jumpers no)
		(fp_poly
			(pts
				(xy -0.2794 -0.1016) (xy 0.2794 -0.1016) (xy 0.2794 0.9906) (xy -0.2794 0.9906)
			)
			(stroke
				(width 0)
				(type default)
			)
			(fill no)
			(layer "F.CrtYd")
		)
		(fp_line
			(start 0.2794 -0.1016)
			(end -0.2794 -0.1016)
			(stroke
				(width 0.1)
				(type default)
			)
			(layer "F.Fab")
		)
		(fp_line
			(start -0.2794 -0.1016)
			(end -0.2794 0.9906)
			(stroke
				(width 0.1)
				(type default)
			)
			(layer "F.Fab")
		)
		(fp_line
			(start 0.2794 0.9906)
			(end 0.2794 -0.1016)
			(stroke
				(width 0.1)
				(type default)
			)
			(layer "F.Fab")
		)
		(fp_line
			(start -0.2794 0.9906)
			(end 0.2794 0.9906)
			(stroke
				(width 0.1)
				(type default)
			)
			(layer "F.Fab")
		)
		(pad "1" smd rect
			(at 0 0 90)
			(size 0.508 0.508)
			(layers "F.Cu" "F.Mask" "F.Paste")
			(net "CLK_100M_CPU0_PE_REFCLK_R_DN")
		)
		(pad "2" smd rect
			(at 0 0.889 90)
			(size 0.508 0.508)
			(layers "F.Cu" "F.Mask" "F.Paste")
			(net "CLK_100M_CPU0_PE_REFCLK_DN")
		)
		(zone
			(layer "F.Cu")
			(hatch none 0.5)
			(connect_pads
				(clearance 0)
			)
			(min_thickness 0.25)
			(keepout
				(tracks allowed)
				(vias not_allowed)
				(pads allowed)
				(copperpour not_allowed)
				(footprints allowed)
			)
			(placement
				(enabled no)
				(sheetname "")
			)
			(fill
				(thermal_gap 0.5)
				(thermal_bridge_width 0.5)
				(island_removal_mode 0)
			)
			(polygon
				(pts
					(xy 175.641 -84.963) (xy 175.641 -85.471) (xy 176.022 -85.471) (xy 176.022 -84.963)
				)
			)
		)
		(zone
			(layer "F.Cu")
			(hatch none 0.5)
			(connect_pads
				(clearance 0)
			)
			(min_thickness 0.25)
			(keepout
				(tracks not_allowed)
				(vias allowed)
				(pads allowed)
				(copperpour not_allowed)
				(footprints allowed)
			)
			(placement
				(enabled no)
				(sheetname "")
			)
			(fill
				(thermal_gap 0.5)
				(thermal_bridge_width 0.5)
				(island_removal_mode 0)
			)
			(polygon
				(pts
					(xy 176.022 -84.963) (xy 176.022 -85.471) (xy 175.641 -85.471) (xy 175.641 -84.963)
				)
			)
		)
	)
	(footprint ""
		(layer "F.Cu")
		(at 452.767192 -23.605998)
		(property "Reference" "EU25F2"
			(at -0.256286 -1.613408 0)
			(unlocked yes)
			(layer "F.SilkS")
			(effects
				(font
					(size 1.27 0.964946)
					(thickness 0.000001)
				)
				(justify left)
			)
		)
		(property "Value" ""
			(at 0 0 0)
			(layer "F.Fab")
			(effects
				(font
					(size 1.27 1.27)
				)
			)
		)
		(duplicate_pad_numbers_are_jumpers no)
		(fp_circle
			(center -0.835152 -0.417322)
			(end -0.708406 -0.417322)
			(stroke
				(width 0.254)
				(type default)
			)
			(fill no)
			(layer "F.SilkS")
		)
		(fp_poly
			(pts
				(xy -0.064516 -1.0922) (xy -0.064516 -0.3302) (xy 0.697484 -1.0922)
			)
			(stroke
				(width 0)
				(type default)
			)
			(fill yes)
			(layer "F.SilkS")
		)
		(fp_rect
			(start 0.597408 2.295398)
			(end 2.273808 -0.295402)
			(stroke
				(width 0)
				(type default)
			)
			(fill yes)
			(layer "F.Paste")
		)
		(fp_rect
			(start -0.064516 2.500122)
			(end 2.935478 -0.500126)
			(stroke
				(width 0)
				(type default)
			)
			(fill no)
			(layer "F.CrtYd")
		)
		(fp_line
			(start -0.064516 -0.500126)
			(end 2.935478 -0.500126)
			(stroke
				(width 0.1)
				(type default)
			)
			(layer "F.Fab")
		)
		(fp_line
			(start -0.064516 2.500122)
			(end -0.064516 -0.500126)
			(stroke
				(width 0.1)
				(type default)
			)
			(layer "F.Fab")
		)
		(fp_line
			(start 2.935478 -0.500126)
			(end 2.935478 2.500122)
			(stroke
				(width 0.1)
				(type default)
			)
			(layer "F.Fab")
		)
		(fp_line
			(start 2.935478 2.500122)
			(end -0.064516 2.500122)
			(stroke
				(width 0.1)
				(type default)
			)
			(layer "F.Fab")
		)
		(fp_circle
			(center -0.835152 -0.417322)
			(end -0.708406 -0.417322)
			(stroke
				(width 0.254)
				(type default)
			)
			(fill no)
			(layer "F.Fab")
		)
		(pad "1" smd rect
			(at 0 0)
			(size 0.6858 0.3048)
			(layers "F.Cu" "F.Mask" "F.Paste")
			(net "P2V5_AUX_BMC")
		)
		(pad "2" smd rect
			(at 0 0.500126)
			(size 0.6858 0.3048)
			(layers "F.Cu" "F.Mask" "F.Paste")
			(net "P2V5_AUX_BMC")
		)
		(pad "3" smd rect
			(at 0 0.999998)
			(size 0.6858 0.3048)
			(layers "F.Cu" "F.Mask" "F.Paste")
			(net "P2V5_AUX_BMC")
		)
		(pad "4" smd rect
			(at 0 1.500124)
			(size 0.6858 0.3048)
			(layers "F.Cu" "F.Mask" "F.Paste")
			(net "VR_P2V5_BMC_STBY_FB")
		)
		(pad "5" smd rect
			(at 0 1.999996)
			(size 0.6858 0.3048)
			(layers "F.Cu" "F.Mask" "F.Paste")
			(net "PWRGD_P2V5_BMC_STBY_R")
		)
		(pad "6" smd rect
			(at 2.871216 1.999996)
			(size 0.6858 0.3048)
			(layers "F.Cu" "F.Mask" "F.Paste")
			(net "PWRGD_P3V3_STBY")
		)
		(pad "7" smd rect
			(at 2.871216 1.500124)
			(size 0.6858 0.3048)
			(layers "F.Cu" "F.Mask" "F.Paste")
			(net "P3V3_STBY")
		)
		(pad "8" smd rect
			(at 2.871216 0.999998)
			(size 0.6858 0.3048)
			(layers "F.Cu" "F.Mask" "F.Paste")
			(net "P3V3_STBY")
		)
		(pad "9" smd rect
			(at 2.871216 0.500126)
			(size 0.6858 0.3048)
			(layers "F.Cu" "F.Mask" "F.Paste")
			(net "P3V3_STBY")
		)
		(pad "10" smd rect
			(at 2.871216 0)
			(size 0.6858 0.3048)
			(layers "F.Cu" "F.Mask" "F.Paste")
			(net "P3V3_STBY")
		)
		(pad "11" smd rect
			(at 1.435608 0.999998)
			(size 1.6764 2.5908)
			(layers "F.Cu" "F.Mask" "F.Paste")
			(net "GND")
		)
	)
	(footprint ""
		(layer "F.Cu")
		(at 96.949768 -79.6036 180)
		(property "Reference" "C2D12"
			(at 0 0 180)
			(layer "F.SilkS")
			(hide yes)
			(effects
				(font
					(size 1.27 1.27)
				)
			)
		)
		(property "Value" ""
			(at 0 0 180)
			(layer "F.Fab")
			(effects
				(font
					(size 1.27 1.27)
				)
			)
		)
		(duplicate_pad_numbers_are_jumpers no)
		(fp_poly
			(pts
				(xy -0.4953 -0.2032) (xy 0.4953 -0.2032) (xy 0.4953 1.6002) (xy -0.4953 1.6002)
			)
			(stroke
				(width 0)
				(type default)
			)
			(fill no)
			(layer "F.CrtYd")
		)
		(fp_line
			(start 0.4953 1.6002)
			(end -0.4953 1.6002)
			(stroke
				(width 0.1)
				(type default)
			)
			(layer "F.Fab")
		)
		(fp_line
			(start 0.4953 -0.2032)
			(end 0.4953 1.6002)
			(stroke
				(width 0.1)
				(type default)
			)
			(layer "F.Fab")
		)
		(fp_line
			(start -0.4953 1.6002)
			(end -0.4953 -0.2032)
			(stroke
				(width 0.1)
				(type default)
			)
			(layer "F.Fab")
		)
		(fp_line
			(start -0.4953 -0.2032)
			(end 0.4953 -0.2032)
			(stroke
				(width 0.1)
				(type default)
			)
			(layer "F.Fab")
		)
		(pad "1" smd rect
			(at 0 0 180)
			(size 0.762 0.889)
			(layers "F.Cu" "F.Mask" "F.Paste")
			(net "PVCCIN_CPU1")
		)
		(pad "2" smd rect
			(at 0 1.397 180)
			(size 0.762 0.889)
			(layers "F.Cu" "F.Mask" "F.Paste")
			(net "GND")
		)
		(zone
			(layer "F.Cu")
			(hatch none 0.5)
			(connect_pads
				(clearance 0)
			)
			(min_thickness 0.25)
			(keepout
				(tracks not_allowed)
				(vias allowed)
				(pads allowed)
				(copperpour not_allowed)
				(footprints allowed)
			)
			(placement
				(enabled no)
				(sheetname "")
			)
			(fill
				(thermal_gap 0.5)
				(thermal_bridge_width 0.5)
				(island_removal_mode 0)
			)
			(polygon
				(pts
					(xy 97.330768 -80.0481) (xy 96.568768 -80.0481) (xy 96.568768 -80.5561) (xy 97.330768 -80.5561)
				)
			)
		)
	)
	(footprint ""
		(layer "F.Cu")
		(at 457.923392 -42.401998 -90)
		(property "Reference" "C9E10"
			(at 0 0 270)
			(layer "F.SilkS")
			(hide yes)
			(effects
				(font
					(size 1.27 1.27)
				)
			)
		)
		(property "Value" ""
			(at 0 0 270)
			(layer "F.Fab")
			(effects
				(font
					(size 1.27 1.27)
				)
			)
		)
		(duplicate_pad_numbers_are_jumpers no)
		(fp_poly
			(pts
				(xy -0.4953 -0.2032) (xy 0.4953 -0.2032) (xy 0.4953 1.6002) (xy -0.4953 1.6002)
			)
			(stroke
				(width 0)
				(type default)
			)
			(fill no)
			(layer "F.CrtYd")
		)
		(fp_line
			(start -0.4953 1.6002)
			(end -0.4953 -0.2032)
			(stroke
				(width 0.1)
				(type default)
			)
			(layer "F.Fab")
		)
		(fp_line
			(start 0.4953 1.6002)
			(end -0.4953 1.6002)
			(stroke
				(width 0.1)
				(type default)
			)
			(layer "F.Fab")
		)
		(fp_line
			(start -0.4953 -0.2032)
			(end 0.4953 -0.2032)
			(stroke
				(width 0.1)
				(type default)
			)
			(layer "F.Fab")
		)
		(fp_line
			(start 0.4953 -0.2032)
			(end 0.4953 1.6002)
			(stroke
				(width 0.1)
				(type default)
			)
			(layer "F.Fab")
		)
		(pad "1" smd rect
			(at 0 0 270)
			(size 0.762 0.889)
			(layers "F.Cu" "F.Mask" "F.Paste")
			(net "P1V15_AUX_BMC")
		)
		(pad "2" smd rect
			(at 0 1.397 270)
			(size 0.762 0.889)
			(layers "F.Cu" "F.Mask" "F.Paste")
			(net "GND")
		)
		(zone
			(layer "F.Cu")
			(hatch none 0.5)
			(connect_pads
				(clearance 0)
			)
			(min_thickness 0.25)
			(keepout
				(tracks not_allowed)
				(vias allowed)
				(pads allowed)
				(copperpour not_allowed)
				(footprints allowed)
			)
			(placement
				(enabled no)
				(sheetname "")
			)
			(fill
				(thermal_gap 0.5)
				(thermal_bridge_width 0.5)
				(island_removal_mode 0)
			)
			(polygon
				(pts
					(xy 457.478892 -42.782998) (xy 457.478892 -42.020998) (xy 456.970892 -42.020998) (xy 456.970892 -42.782998)
				)
			)
		)
	)
	(footprint ""
		(layer "F.Cu")
		(at 49.4284 -59.143392 180)
		(property "Reference" "C1E9"
			(at 0 0 180)
			(layer "F.SilkS")
			(hide yes)
			(effects
				(font
					(size 1.27 1.27)
				)
			)
		)
		(property "Value" ""
			(at 0 0 180)
			(layer "F.Fab")
			(effects
				(font
					(size 1.27 1.27)
				)
			)
		)
		(duplicate_pad_numbers_are_jumpers no)
		(fp_poly
			(pts
				(xy -0.4953 -0.2032) (xy 0.4953 -0.2032) (xy 0.4953 1.6002) (xy -0.4953 1.6002)
			)
			(stroke
				(width 0)
				(type default)
			)
			(fill no)
			(layer "F.CrtYd")
		)
		(fp_line
			(start 0.4953 1.6002)
			(end -0.4953 1.6002)
			(stroke
				(width 0.1)
				(type default)
			)
			(layer "F.Fab")
		)
		(fp_line
			(start 0.4953 -0.2032)
			(end 0.4953 1.6002)
			(stroke
				(width 0.1)
				(type default)
			)
			(layer "F.Fab")
		)
		(fp_line
			(start -0.4953 1.6002)
			(end -0.4953 -0.2032)
			(stroke
				(width 0.1)
				(type default)
			)
			(layer "F.Fab")
		)
		(fp_line
			(start -0.4953 -0.2032)
			(end 0.4953 -0.2032)
			(stroke
				(width 0.1)
				(type default)
			)
			(layer "F.Fab")
		)
		(pad "1" smd rect
			(at 0 0 180)
			(size 0.762 0.889)
			(layers "F.Cu" "F.Mask" "F.Paste")
			(net "PVCCIN_CPU1")
		)
		(pad "2" smd rect
			(at 0 1.397 180)
			(size 0.762 0.889)
			(layers "F.Cu" "F.Mask" "F.Paste")
			(net "GND")
		)
		(zone
			(layer "F.Cu")
			(hatch none 0.5)
			(connect_pads
				(clearance 0)
			)
			(min_thickness 0.25)
			(keepout
				(tracks not_allowed)
				(vias allowed)
				(pads allowed)
				(copperpour not_allowed)
				(footprints allowed)
			)
			(placement
				(enabled no)
				(sheetname "")
			)
			(fill
				(thermal_gap 0.5)
				(thermal_bridge_width 0.5)
				(island_removal_mode 0)
			)
			(polygon
				(pts
					(xy 49.8094 -59.587892) (xy 49.0474 -59.587892) (xy 49.0474 -60.095892) (xy 49.8094 -60.095892)
				)
			)
		)
	)
	(footprint ""
		(layer "F.Cu")
		(at 487.554016 -155.702254 -90)
		(property "Reference" "S9A1"
			(at -1.97485 3.5941 0)
			(unlocked yes)
			(layer "F.SilkS")
			(effects
				(font
					(size 0.7874 0.5842)
					(thickness 0.1524)
				)
				(justify left)
			)
		)
		(property "Value" ""
			(at 0 0 270)
			(layer "F.Fab")
			(effects
				(font
					(size 1.27 1.27)
				)
			)
		)
		(duplicate_pad_numbers_are_jumpers no)
		(fp_line
			(start 1.800098 5.3721)
			(end 3.022092 5.3721)
			(stroke
				(width 0.1524)
				(type default)
			)
			(layer "F.SilkS")
		)
		(fp_line
			(start -0.7112 0.978154)
			(end -0.7112 3.52044)
			(stroke
				(width 0.1524)
				(type default)
			)
			(layer "F.SilkS")
		)
		(fp_line
			(start 5.5372 0.973836)
			(end 5.5372 3.52044)
			(stroke
				(width 0.1524)
				(type default)
			)
			(layer "F.SilkS")
		)
		(fp_line
			(start 3.024632 -0.8763)
			(end 1.800098 -0.8763)
			(stroke
				(width 0.1524)
				(type default)
			)
			(layer "F.SilkS")
		)
		(fp_circle
			(center -1.972818 -0.651002)
			(end -1.972818 -0.778002)
			(stroke
				(width 0.254)
				(type default)
			)
			(fill no)
			(layer "F.SilkS")
		)
		(fp_rect
			(start -0.7112 5.3721)
			(end 5.5372 -0.8763)
			(stroke
				(width 0)
				(type default)
			)
			(fill no)
			(layer "F.CrtYd")
		)
		(fp_line
			(start -0.7112 5.3721)
			(end -0.7112 -0.8763)
			(stroke
				(width 0.1)
				(type default)
			)
			(layer "F.Fab")
		)
		(fp_line
			(start 5.5372 5.3721)
			(end -0.7112 5.3721)
			(stroke
				(width 0.1)
				(type default)
			)
			(layer "F.Fab")
		)
		(fp_line
			(start -0.7112 -0.8763)
			(end 5.5372 -0.8763)
			(stroke
				(width 0.1)
				(type default)
			)
			(layer "F.Fab")
		)
		(fp_line
			(start 5.5372 -0.8763)
			(end 5.5372 5.3721)
			(stroke
				(width 0.1)
				(type default)
			)
			(layer "F.Fab")
		)
		(fp_circle
			(center -1.972818 -0.651002)
			(end -1.972818 -0.778002)
			(stroke
				(width 0.254)
				(type default)
			)
			(fill no)
			(layer "F.Fab")
		)
		(fp_text user "4"
			(at 5.881624 5.809996 0)
			(unlocked yes)
			(layer "F.SilkS")
			(effects
				(font
					(size 0.7874 0.5842)
					(thickness 0.1524)
				)
				(justify left)
			)
		)
		(fp_text user "2"
			(at 5.373624 -0.735584 0)
			(unlocked yes)
			(layer "F.SilkS")
			(effects
				(font
					(size 0.7874 0.5842)
					(thickness 0.1524)
				)
				(justify left)
			)
		)
		(fp_text user "4"
			(at 6.354064 3.663696 0)
			(unlocked yes)
			(layer "F.Fab")
			(effects
				(font
					(size 0.635 0.635)
					(thickness 0.1524)
				)
				(justify left)
			)
		)
		(fp_text user "2"
			(at 6.338316 1.57861 0)
			(unlocked yes)
			(layer "F.Fab")
			(effects
				(font
					(size 0.635 0.635)
					(thickness 0.1524)
				)
				(justify left)
			)
		)
		(pad "1" smd rect
			(at 0 0 270)
			(size 2.921 1.27)
			(layers "F.Cu" "F.Mask" "F.Paste")
			(net "FM_DEBUG_RST_BTN_N")
		)
		(pad "2" smd rect
			(at 4.826 0 270)
			(size 2.921 1.27)
			(layers "F.Cu" "F.Mask" "F.Paste")
			(net "FM_DEBUG_RST_BTN_N")
		)
		(pad "3" smd rect
			(at 0 4.4958 270)
			(size 2.921 1.27)
			(layers "F.Cu" "F.Mask" "F.Paste")
			(net "GND")
		)
		(pad "4" smd rect
			(at 4.826 4.4958 270)
			(size 2.921 1.27)
			(layers "F.Cu" "F.Mask" "F.Paste")
			(net "GND")
		)
	)
	(footprint ""
		(layer "F.Cu")
		(at 427.355 -22.86 90)
		(property "Reference" "R10W3"
			(at -0.8382 -0.67818 90)
			(unlocked yes)
			(layer "F.SilkS")
			(effects
				(font
					(size 0.4064 0.254)
					(thickness 0.1524)
				)
				(justify left)
			)
		)
		(property "Value" ""
			(at 0 0 90)
			(layer "F.Fab")
			(effects
				(font
					(size 1.27 1.27)
				)
			)
		)
		(duplicate_pad_numbers_are_jumpers no)
		(fp_poly
			(pts
				(xy -0.2794 -0.1016) (xy 0.2794 -0.1016) (xy 0.2794 0.9906) (xy -0.2794 0.9906)
			)
			(stroke
				(width 0)
				(type default)
			)
			(fill no)
			(layer "F.CrtYd")
		)
		(fp_line
			(start 0.2794 -0.1016)
			(end -0.2794 -0.1016)
			(stroke
				(width 0.1)
				(type default)
			)
			(layer "F.Fab")
		)
		(fp_line
			(start -0.2794 -0.1016)
			(end -0.2794 0.9906)
			(stroke
				(width 0.1)
				(type default)
			)
			(layer "F.Fab")
		)
		(fp_line
			(start 0.2794 0.9906)
			(end 0.2794 -0.1016)
			(stroke
				(width 0.1)
				(type default)
			)
			(layer "F.Fab")
		)
		(fp_line
			(start -0.2794 0.9906)
			(end 0.2794 0.9906)
			(stroke
				(width 0.1)
				(type default)
			)
			(layer "F.Fab")
		)
		(pad "1" smd rect
			(at 0 0 90)
			(size 0.508 0.508)
			(layers "F.Cu" "F.Mask" "F.Paste")
			(net "P5V_STBY")
		)
		(pad "2" smd rect
			(at 0 0.889 90)
			(size 0.508 0.508)
			(layers "F.Cu" "F.Mask" "F.Paste")
			(net "PUMP_PWM_OUT_R")
		)
		(zone
			(layer "F.Cu")
			(hatch none 0.5)
			(connect_pads
				(clearance 0)
			)
			(min_thickness 0.25)
			(keepout
				(tracks allowed)
				(vias not_allowed)
				(pads allowed)
				(copperpour not_allowed)
				(footprints allowed)
			)
			(placement
				(enabled no)
				(sheetname "")
			)
			(fill
				(thermal_gap 0.5)
				(thermal_bridge_width 0.5)
				(island_removal_mode 0)
			)
			(polygon
				(pts
					(xy 427.609 -22.606) (xy 427.609 -23.114) (xy 427.99 -23.114) (xy 427.99 -22.606)
				)
			)
		)
		(zone
			(layer "F.Cu")
			(hatch none 0.5)
			(connect_pads
				(clearance 0)
			)
			(min_thickness 0.25)
			(keepout
				(tracks not_allowed)
				(vias allowed)
				(pads allowed)
				(copperpour not_allowed)
				(footprints allowed)
			)
			(placement
				(enabled no)
				(sheetname "")
			)
			(fill
				(thermal_gap 0.5)
				(thermal_bridge_width 0.5)
				(island_removal_mode 0)
			)
			(polygon
				(pts
					(xy 427.99 -22.606) (xy 427.99 -23.114) (xy 427.609 -23.114) (xy 427.609 -22.606)
				)
			)
		)
	)
)
